(kicad_pcb
	(version 20211014)
	(generator pcbnew)
	(general
    (thickness 1.6)
  )
	(paper "A4")
	(title_block
    (title "SA800U (Snapdragon 845) Baseboard")
    (date "2023-10-19")
    (rev "1.0.3")
    (company "Antmicro Ltd.")
    (comment 1 "www.antmicro.com")
		(comment 9 "footprints 203-210 of 589")
	)
	(layers
    (0 "F.Cu" signal)
    (1 "In1.Cu" power)
    (2 "In2.Cu" signal)
    (3 "In3.Cu" signal)
    (4 "In4.Cu" power)
    (31 "B.Cu" signal)
    (32 "B.Adhes" user "B.Adhesive")
    (33 "F.Adhes" user "F.Adhesive")
    (34 "B.Paste" user)
    (35 "F.Paste" user)
    (36 "B.SilkS" user "B.Silkscreen")
    (37 "F.SilkS" user "F.Silkscreen")
    (38 "B.Mask" user)
    (39 "F.Mask" user)
    (40 "Dwgs.User" user "User.Drawings")
    (41 "Cmts.User" user "User.Comments")
    (42 "Eco1.User" user "User.Eco1")
    (43 "Eco2.User" user "User.Eco2")
    (44 "Edge.Cuts" user)
    (45 "Margin" user)
    (46 "B.CrtYd" user "B.Courtyard")
    (47 "F.CrtYd" user "F.Courtyard")
    (48 "B.Fab" user)
    (49 "F.Fab" user)
  )
	(footprint "sa800u-baseboard-hw-footprints:L_0603_1608Metric" (layer "F.Cu")
    (tedit 5D5D3F54)
    (at 146.8 119.4 180)
    (property "Author" "Antmicro")
    (property "IMax" "")
    (property "ISat" "")
    (property "License" "Apache-2.0")
    (property "MPN" "BRC1608TR35M")
    (property "Manufacturer" "Taiyo Yuden")
    (property "Sheetfile" "hdmi-converter.kicad_sch")
    (property "Sheetname" "HDMI converter")
    (property "Size" "")
    (property "Val" "350n/1.4A")
    (attr smd)
    (fp_text reference "L5" (at -1.1 -0.47 180) (layer "F.SilkS")
      (effects (font (size 0.7 0.7) (thickness 0.15)) (justify left bottom))
    )
    (fp_text value "L_350n_1.4A_0603" (at 0 2 180) (layer "F.Fab")
      (effects (font (size 0.7 0.7) (thickness 0.15)) (justify left bottom))
    )
    (fp_text user "License: Apache-2.0" (at -1.9 5.75 180) (layer "F.Fab") hide
      (effects (font (size 0.7 0.7) (thickness 0.15)) (justify left bottom))
    )
    (fp_text user "${REFERENCE}" (at -1.9 3.1 180) (layer "F.Fab") hide
      (effects (font (size 0.7 0.7) (thickness 0.15)) (justify left bottom))
    )
    (fp_text user "Author: Antmicro" (at -1.9 4.4 180) (layer "F.Fab") hide
      (effects (font (size 0.7 0.7) (thickness 0.15)) (justify left bottom))
    )
    (fp_line (start -0.25 -0.45) (end 0.25 -0.45) (layer "F.SilkS") (width 0.1))
    (fp_line (start -0.25 0.45) (end 0.25 0.45) (layer "F.SilkS") (width 0.1))
    (fp_rect (start -1.15 -0.75) (end 1.15 0.75) (layer "F.CrtYd") (width 0.05) (fill none))
    (fp_rect (start -0.8 -0.4) (end 0.8 0.4) (layer "F.Fab") (width 0.1) (fill none))
    (pad "1" smd roundrect (at -0.625 0 180) (size 0.55 1) (layers "F.Cu" "F.Paste" "F.Mask") (roundrect_rratio 0.15)
      (net 138 "1V2_SYS") (pintype "passive"))
    (pad "2" smd roundrect (at 0.625 0 180) (size 0.55 1) (layers "F.Cu" "F.Paste" "F.Mask") (roundrect_rratio 0.15)
      (net 189 "/HDMI converter/LT9611_VCC12_RX") (pintype "passive"))
  )
	(footprint "sa800u-baseboard-hw-footprints:R_0402_1005Metric" (layer "F.Cu")
    (tedit 5FD9C158)
    (at 144.6 133.05 -90)
    (descr "Resistor SMD 0402")
    (tags "resistor SMD 0402")
    (property "Author" "Antmicro")
    (property "License" "Apache-2.0")
    (property "MPN" "CR0402-FX-50R0GLF")
    (property "Manufacturer" "Bourns")
    (property "Sheetfile" "hdmi-converter.kicad_sch")
    (property "Sheetname" "HDMI converter")
    (property "Tolerance" "1%")
    (property "Val" "50R")
    (attr smd)
    (fp_text reference "R42" (at -4.58 16.09 -90) (layer "F.SilkS")
      (effects (font (size 0.7 0.7) (thickness 0.15)) (justify left bottom))
    )
    (fp_text value "R_50R_0402" (at 0 1.4 -90) (layer "F.Fab")
      (effects (font (size 0.7 0.7) (thickness 0.15)) (justify left bottom))
    )
    (fp_text user "Author: Antmicro" (at -0.95 4.169 -90) (layer "F.Fab") hide
      (effects (font (size 0.7 0.7) (thickness 0.15)) (justify left bottom))
    )
    (fp_text user "License: Apache-2.0" (at -0.95 5.169 -90) (layer "F.Fab") hide
      (effects (font (size 0.7 0.7) (thickness 0.15)) (justify left bottom))
    )
    (fp_text user "${REFERENCE}" (at -0.95 3.168 -90) (layer "F.Fab") hide
      (effects (font (size 0.7 0.7) (thickness 0.15)) (justify left bottom))
    )
    (fp_rect (start -0.93 -0.47) (end 0.93 0.47) (layer "F.CrtYd") (width 0.05) (fill none))
    (fp_rect (start -0.5 -0.25) (end 0.5 0.25) (layer "F.Fab") (width 0.15) (fill none))
    (pad "1" smd roundrect (at -0.485 0 270) (size 0.59 0.64) (layers "F.Cu" "F.Paste" "F.Mask") (roundrect_rratio 0.25)
      (net 187 "/HDMI converter/LT9611_VCC33_TX") (pintype "passive"))
    (pad "2" smd roundrect (at 0.485 0 270) (size 0.59 0.64) (layers "F.Cu" "F.Paste" "F.Mask") (roundrect_rratio 0.25)
      (net 197 "/HDMI converter/HDMI_TX_D1_P") (pintype "passive"))
  )
	(footprint "sa800u-baseboard-hw-footprints:R_0402_1005Metric" (layer "F.Cu")
    (tedit 5FD9C158)
    (at 141.4 133.05 -90)
    (descr "Resistor SMD 0402")
    (tags "resistor SMD 0402")
    (property "Author" "Antmicro")
    (property "License" "Apache-2.0")
    (property "MPN" "CR0402-FX-50R0GLF")
    (property "Manufacturer" "Bourns")
    (property "Sheetfile" "hdmi-converter.kicad_sch")
    (property "Sheetname" "HDMI converter")
    (property "Tolerance" "1%")
    (property "Val" "50R")
    (attr smd)
    (fp_text reference "R39" (at -4.66 15.86 -90) (layer "F.SilkS")
      (effects (font (size 0.7 0.7) (thickness 0.15)) (justify left bottom))
    )
    (fp_text value "R_50R_0402" (at 0 1.4 -90) (layer "F.Fab")
      (effects (font (size 0.7 0.7) (thickness 0.15)) (justify left bottom))
    )
    (fp_text user "License: Apache-2.0" (at -0.95 5.169 -90) (layer "F.Fab") hide
      (effects (font (size 0.7 0.7) (thickness 0.15)) (justify left bottom))
    )
    (fp_text user "${REFERENCE}" (at -0.95 3.168 -90) (layer "F.Fab") hide
      (effects (font (size 0.7 0.7) (thickness 0.15)) (justify left bottom))
    )
    (fp_text user "Author: Antmicro" (at -0.95 4.169 -90) (layer "F.Fab") hide
      (effects (font (size 0.7 0.7) (thickness 0.15)) (justify left bottom))
    )
    (fp_rect (start -0.93 -0.47) (end 0.93 0.47) (layer "F.CrtYd") (width 0.05) (fill none))
    (fp_rect (start -0.5 -0.25) (end 0.5 0.25) (layer "F.Fab") (width 0.15) (fill none))
    (pad "1" smd roundrect (at -0.485 0 270) (size 0.59 0.64) (layers "F.Cu" "F.Paste" "F.Mask") (roundrect_rratio 0.25)
      (net 187 "/HDMI converter/LT9611_VCC33_TX") (pintype "passive"))
    (pad "2" smd roundrect (at 0.485 0 270) (size 0.59 0.64) (layers "F.Cu" "F.Paste" "F.Mask") (roundrect_rratio 0.25)
      (net 202 "/HDMI converter/HDMI_TX_D0_P") (pintype "passive"))
  )
	(footprint "sa800u-baseboard-hw-footprints:R_0402_1005Metric" (layer "F.Cu")
    (tedit 5FD9C158)
    (at 139.5 133.05 -90)
    (descr "Resistor SMD 0402")
    (tags "resistor SMD 0402")
    (property "Author" "Antmicro")
    (property "License" "Apache-2.0")
    (property "MPN" "CR0402-FX-50R0GLF")
    (property "Manufacturer" "Bourns")
    (property "Sheetfile" "hdmi-converter.kicad_sch")
    (property "Sheetname" "HDMI converter")
    (property "Tolerance" "1%")
    (property "Val" "50R")
    (attr smd)
    (fp_text reference "R38" (at -4.631 15.86 -90) (layer "F.SilkS")
      (effects (font (size 0.7 0.7) (thickness 0.15)) (justify left bottom))
    )
    (fp_text value "R_50R_0402" (at 0 1.4 -90) (layer "F.Fab")
      (effects (font (size 0.7 0.7) (thickness 0.15)) (justify left bottom))
    )
    (fp_text user "${REFERENCE}" (at -0.95 3.168 -90) (layer "F.Fab") hide
      (effects (font (size 0.7 0.7) (thickness 0.15)) (justify left bottom))
    )
    (fp_text user "Author: Antmicro" (at -0.95 4.169 -90) (layer "F.Fab") hide
      (effects (font (size 0.7 0.7) (thickness 0.15)) (justify left bottom))
    )
    (fp_text user "License: Apache-2.0" (at -0.95 5.169 -90) (layer "F.Fab") hide
      (effects (font (size 0.7 0.7) (thickness 0.15)) (justify left bottom))
    )
    (fp_rect (start -0.93 -0.47) (end 0.93 0.47) (layer "F.CrtYd") (width 0.05) (fill none))
    (fp_rect (start -0.5 -0.25) (end 0.5 0.25) (layer "F.Fab") (width 0.15) (fill none))
    (pad "1" smd roundrect (at -0.485 0 270) (size 0.59 0.64) (layers "F.Cu" "F.Paste" "F.Mask") (roundrect_rratio 0.25)
      (net 187 "/HDMI converter/LT9611_VCC33_TX") (pintype "passive"))
    (pad "2" smd roundrect (at 0.485 0 270) (size 0.59 0.64) (layers "F.Cu" "F.Paste" "F.Mask") (roundrect_rratio 0.25)
      (net 204 "/HDMI converter/HDMI_TX_D0_N") (pintype "passive"))
  )
	(footprint "sa800u-baseboard-hw-footprints:C_0402_1005Metric" (layer "F.Cu")
    (tedit 616D63CF)
    (at 132.888164 125.012952 90)
    (descr "Capacitor SMD 0402")
    (tags "capacitor SMD 0402")
    (property "Author" "Antmicro")
    (property "Dielectric" "X5R")
    (property "License" "Apache-2.0")
    (property "MPN" "GRM155R61H104KE14D")
    (property "Manufacturer" "Murata")
    (property "Sheetfile" "hdmi-converter.kicad_sch")
    (property "Sheetname" "HDMI converter")
    (property "Val" "100n")
    (property "Voltage" "50V")
    (attr smd)
    (fp_text reference "C18" (at -1.107048 -2.498164 90) (layer "F.SilkS")
      (effects (font (size 0.7 0.7) (thickness 0.15)) (justify left bottom))
    )
    (fp_text value "C_100n_0402" (at 0 1.4 90) (layer "F.Fab")
      (effects (font (size 0.7 0.7) (thickness 0.15)) (justify left bottom))
    )
    (fp_text user "License: Apache-2.0" (at -0.932 5.17 90) (layer "F.Fab") hide
      (effects (font (size 0.7 0.7) (thickness 0.15)) (justify left bottom))
    )
    (fp_text user "Author: Antmicro" (at -0.932 4.17 90) (layer "F.Fab") hide
      (effects (font (size 0.7 0.7) (thickness 0.15)) (justify left bottom))
    )
    (fp_text user "${REFERENCE}" (at -0.932 3.168 90) (layer "F.Fab") hide
      (effects (font (size 0.7 0.7) (thickness 0.15)) (justify left bottom))
    )
    (fp_rect (start -0.94 -0.47) (end 0.94 0.47) (layer "F.CrtYd") (width 0.05) (fill none))
    (fp_rect (start -0.499 -0.249) (end 0.499 0.249) (layer "F.Fab") (width 0.15) (fill none))
    (pad "1" smd roundrect (at -0.484 0 90) (size 0.59 0.64) (layers "F.Cu" "F.Paste" "F.Mask") (roundrect_rratio 0.25)
      (net 132 "VREG_S4A_1V8") (pintype "passive"))
    (pad "2" smd roundrect (at 0.484 0 90) (size 0.59 0.64) (layers "F.Cu" "F.Paste" "F.Mask") (roundrect_rratio 0.25)
      (net 1 "GND") (pintype "passive"))
  )
	(footprint "sa800u-baseboard-hw-footprints:L_Murata_025020_0605Metric" (layer "F.Cu")
    (tedit 61AA2C4F)
    (at 137.25 136.85 -90)
    (property "Author" "Antmicro")
    (property "License" "Apache-2.0")
    (property "MPN" "NFP0QHB242HS2D")
    (property "Manufacturer" "Murata")
    (property "Sheetfile" "hdmi-converter.kicad_sch")
    (property "Sheetname" "HDMI converter")
    (attr smd)
    (fp_text reference "L10" (at -4.611 15.5 -90) (layer "F.SilkS")
      (effects (font (size 0.7 0.7) (thickness 0.15)) (justify left bottom))
    )
    (fp_text value "NFP0QHB242HS2D" (at 0 1.55 -90) (layer "F.Fab")
      (effects (font (size 0.7 0.7) (thickness 0.15)) (justify left bottom))
    )
    (fp_text user "License: Apache-2.0" (at -1.027 5.805 -90) (layer "F.Fab") hide
      (effects (font (size 0.7 0.7) (thickness 0.15)) (justify left bottom))
    )
    (fp_text user "${REFERENCE}" (at -1.027 3.406 -90) (layer "F.Fab") hide
      (effects (font (size 0.7 0.7) (thickness 0.15)) (justify left bottom))
    )
    (fp_text user "Author: Antmicro" (at -1.027 4.605 -90) (layer "F.Fab") hide
      (effects (font (size 0.7 0.7) (thickness 0.15)) (justify left bottom))
    )
    (fp_line (start 0.276 -0.45) (end -0.276 -0.45) (layer "F.SilkS") (width 0.15))
    (fp_line (start -0.276 0.45) (end 0.276 0.45) (layer "F.SilkS") (width 0.15))
    (fp_circle (center -0.5 -0.5) (end -0.449 -0.5) (layer "F.SilkS") (width 0.15) (fill solid))
    (fp_rect (start -0.5 -0.6) (end 0.5 0.6) (layer "F.CrtYd") (width 0.05) (fill none))
    (fp_line (start 0.275 0.349) (end 0.275 -0.351) (layer "F.Fab") (width 0.15))
    (fp_line (start 0.275 -0.351) (end -0.277 -0.351) (layer "F.Fab") (width 0.15))
    (fp_line (start -0.277 -0.351) (end -0.277 0.349) (layer "F.Fab") (width 0.15))
    (fp_line (start -0.277 0.349) (end 0.275 0.349) (layer "F.Fab") (width 0.15))
    (pad "1" smd rect (at -0.25 -0.24 270) (size 0.3 0.23) (layers "F.Cu" "F.Paste" "F.Mask")
      (net 206 "/HDMI converter/HDMI_CLK_P") (pinfunction "1") (pintype "passive"))
    (pad "2" smd rect (at 0.248 -0.24 270) (size 0.3 0.23) (layers "F.Cu" "F.Paste" "F.Mask")
      (net 237 "/HDMI converter/HDMI_CLK_CONN_P") (pinfunction "2") (pintype "passive"))
    (pad "3" smd rect (at 0.248 0.239 270) (size 0.3 0.23) (layers "F.Cu" "F.Paste" "F.Mask")
      (net 238 "/HDMI converter/HDMI_CLK_CONN_N") (pinfunction "3") (pintype "passive"))
    (pad "4" smd rect (at -0.25 0.239 270) (size 0.3 0.23) (layers "F.Cu" "F.Paste" "F.Mask")
      (net 208 "/HDMI converter/HDMI_CLK_N") (pinfunction "4") (pintype "passive"))
  )
	(footprint "sa800u-baseboard-hw-footprints:C_0402_1005Metric" (layer "F.Cu")
    (tedit 616D63CF)
    (at 147.35 134.95 -90)
    (descr "Capacitor SMD 0402")
    (tags "capacitor SMD 0402")
    (property "Author" "Antmicro")
    (property "Dielectric" "X5R")
    (property "License" "Apache-2.0")
    (property "MPN" "GRM155R61H104KE14D")
    (property "Manufacturer" "Murata")
    (property "Sheetfile" "hdmi-converter.kicad_sch")
    (property "Sheetname" "HDMI converter")
    (property "Val" "100n")
    (property "Voltage" "50V")
    (attr smd)
    (fp_text reference "C50" (at -4.58 16.59 -90) (layer "F.SilkS")
      (effects (font (size 0.7 0.7) (thickness 0.15)) (justify left bottom))
    )
    (fp_text value "C_100n_0402" (at 0 1.4 -90) (layer "F.Fab")
      (effects (font (size 0.7 0.7) (thickness 0.15)) (justify left bottom))
    )
    (fp_text user "${REFERENCE}" (at -0.932 3.168 -90) (layer "F.Fab") hide
      (effects (font (size 0.7 0.7) (thickness 0.15)) (justify left bottom))
    )
    (fp_text user "Author: Antmicro" (at -0.932 4.17 -90) (layer "F.Fab") hide
      (effects (font (size 0.7 0.7) (thickness 0.15)) (justify left bottom))
    )
    (fp_text user "License: Apache-2.0" (at -0.932 5.17 -90) (layer "F.Fab") hide
      (effects (font (size 0.7 0.7) (thickness 0.15)) (justify left bottom))
    )
    (fp_rect (start -0.94 -0.47) (end 0.94 0.47) (layer "F.CrtYd") (width 0.05) (fill none))
    (fp_rect (start -0.499 -0.249) (end 0.499 0.249) (layer "F.Fab") (width 0.15) (fill none))
    (pad "1" smd roundrect (at -0.484 0 270) (size 0.59 0.64) (layers "F.Cu" "F.Paste" "F.Mask") (roundrect_rratio 0.25)
      (net 194 "/HDMI converter/HDMI_TX_D2_P") (pintype "passive"))
    (pad "2" smd roundrect (at 0.484 0 270) (size 0.59 0.64) (layers "F.Cu" "F.Paste" "F.Mask") (roundrect_rratio 0.25)
      (net 193 "/HDMI converter/HDMI_TX2_P") (pintype "passive"))
  )
	(footprint "sa800u-baseboard-hw-footprints:Nexperia_DFN-10_2.5x1mm_P0.5mm" (layer "F.Cu")
    (tedit 6215DC23)
    (at 138.85 139.55 180)
    (property "Author" "Antmicro")
    (property "License" "Apache-2.0")
    (property "MPN" "PUSB3F96X")
    (property "Manufacturer" "Nexperia")
    (property "Sheetfile" "hdmi-converter.kicad_sch")
    (property "Sheetname" "HDMI converter")
    (attr smd)
    (fp_text reference "D4" (at 1.59 0.82 180) (layer "F.SilkS")
      (effects (font (size 0.7 0.7) (thickness 0.15)) (justify left bottom))
    )
    (fp_text value "PUSB3F96X_PASS" (at -0.016 1.705 180) (layer "F.Fab")
      (effects (font (size 0.7 0.7) (thickness 0.15)) (justify left bottom))
    )
    (fp_text user "Author: Antmicro" (at -1.367 4.905 180) (layer "F.Fab") hide
      (effects (font (size 0.7 0.7) (thickness 0.15)) (justify left bottom))
    )
    (fp_text user "License: Apache-2.0" (at -1.367 6.105 180) (layer "F.Fab") hide
      (effects (font (size 0.7 0.7) (thickness 0.15)) (justify left bottom))
    )
    (fp_text user "${REFERENCE}" (at -1.367 3.704 180) (layer "F.Fab") hide
      (effects (font (size 0.7 0.7) (thickness 0.15)) (justify left bottom))
    )
    (fp_line (start 1.233 0.405) (end 1.233 -0.396) (layer "F.SilkS") (width 0.15))
    (fp_line (start -1.266 -0.396) (end -1.266 0.405) (layer "F.SilkS") (width 0.15))
    (fp_circle (center -1.317 0.704) (end -1.266 0.704) (layer "F.SilkS") (width 0.15) (fill solid))
    (fp_rect (start -1.4 -0.7) (end 1.4 0.7) (layer "F.CrtYd") (width 0.05) (fill none))
    (pad "1" smd rect (at -1.016 0.392 180) (size 0.2 0.475) (layers "F.Cu" "F.Paste" "F.Mask")
      (net 239 "/HDMI converter/HDMI_TX0_CONN_P") (pinfunction "CH1") (pintype "passive"))
    (pad "2" smd rect (at -0.517 0.392 180) (size 0.2 0.475) (layers "F.Cu" "F.Paste" "F.Mask")
      (net 236 "/HDMI converter/HDMI_TX0_CONN_N") (pinfunction "CH2") (pintype "passive"))
    (pad "3" smd rect (at -0.016 0.392 180) (size 0.2 0.475) (layers "F.Cu" "F.Paste" "F.Mask")
      (net 1 "GND") (pinfunction "GND") (pintype "passive"))
    (pad "4" smd rect (at 0.482 0.392 180) (size 0.2 0.475) (layers "F.Cu" "F.Paste" "F.Mask")
      (net 237 "/HDMI converter/HDMI_CLK_CONN_P") (pinfunction "CH3") (pintype "passive"))
    (pad "5" smd rect (at 0.982 0.392 180) (size 0.2 0.475) (layers "F.Cu" "F.Paste" "F.Mask")
      (net 238 "/HDMI converter/HDMI_CLK_CONN_N") (pinfunction "CH4") (pintype "passive"))
    (pad "6" smd rect (at 0.982 -0.383) (size 0.2 0.475) (layers "F.Cu" "F.Paste" "F.Mask")
      (net 238 "/HDMI converter/HDMI_CLK_CONN_N") (pinfunction "CH4") (pintype "passive"))
    (pad "7" smd rect (at 0.482 -0.383) (size 0.2 0.475) (layers "F.Cu" "F.Paste" "F.Mask")
      (net 237 "/HDMI converter/HDMI_CLK_CONN_P") (pinfunction "CH3") (pintype "passive"))
    (pad "8" smd rect (at -0.016 -0.383) (size 0.2 0.475) (layers "F.Cu" "F.Paste" "F.Mask")
      (net 1 "GND") (pinfunction "GND") (pintype "passive"))
    (pad "9" smd rect (at -0.517 -0.383) (size 0.2 0.475) (layers "F.Cu" "F.Paste" "F.Mask")
      (net 236 "/HDMI converter/HDMI_TX0_CONN_N") (pinfunction "CH2") (pintype "passive"))
    (pad "10" smd rect (at -1.016 -0.383) (size 0.2 0.475) (layers "F.Cu" "F.Paste" "F.Mask")
      (net 239 "/HDMI converter/HDMI_TX0_CONN_P") (pinfunction "CH1") (pintype "passive"))
  )
)
